FILE_TYPE = CONNECTIVITY;
{Allegro Design Entry HDL 17.2-2016 S081 (4005846) 1/11/2022}
"PAGE_NUMBER" = 190;
0"NC";
1"P3V3_AUX\g";
2"P3V3_AUX\g";
3"PGPPA_AUX\g";
4"PGPPA_AUX\g";
5"PGPPA_AUX\g";
6"PGPPA_AUX\g";
7"GND\g"$PHYS_NET_NAME"P3V3_AUX"VOLTAGE"3.3"CDS_PHYS_NET_NAME"P3V3_AUX";
8"GND\g";
9"GND\g"$PHYS_NET_NAME"P3V3_AUX"VOLTAGE"3.3"CDS_PHYS_NET_NAME"P3V3_AUX";
10"GND\g";
11"GND\g";
12"GND\g";
13"GND\g";
14"FM_ESPI_PLD_R_EN_BUF"CDS_PHYS_NET_NAME"FM_CPU0_SKTOCC_N";
15"NC_ESPI_PLD_R_EN_BUF"CDS_PHYS_NET_NAME"FM_CPU0_SKTOCC_N";
16"FM_ESPI_PLD_R1_EN"CDS_PHYS_NET_NAME"FM_CPU0_SKTOCC_N";
17"ESPI_LPC_LAD0_IO3"CDS_PHYS_NET_NAME"ESPI_LAD0_DATA_IO3";
18"ESPI_LPC_LAD0_IO2"CDS_PHYS_NET_NAME"ESPI_LAD0_DATA_IO3";
19"FM_ESPI_PLD_EN"CDS_PHYS_NET_NAME"FM_CPU0_SKTOCC_N"CDS_PHYS_NET_NAME"FM_CPU0_SKTOCC_N";
20"FM_ESPI_PLD_R_EN_BUF"CDS_PHYS_NET_NAME"FM_CPU0_SKTOCC_N";
21"IRQ_ESPI_LPC_SERIRQ_ALERT_R_N"CDS_PHYS_NET_NAME"FM_CPU0_SKTOCC_N";
22"ESPI_BMC_LPC_RST_N"CDS_PHYS_NET_NAME"FM_CPU0_SKTOCC_N";
23"ESPI_LPC_LAD0_IO1"CDS_PHYS_NET_NAME"ESPI_LAD0_DATA_IO3";
24"JTAG_TRC_PCH_PTI<6>"CDS_PHYS_NET_NAME"JTAG_TRC_PCH_PTI<6>"$PNN"JTAG_TRC_PCH_PTI<6>";
25"ESPI_HOST_LPC_BMC_LFRAME_N"CDS_PHYS_NET_NAME"ESPI_LAD0_DATA_IO3";
26"RST_ESPI_RESET_N_R"CDS_PHYS_NET_NAME"IRQ_LPC_SERIRQ_ESPI_CS1_N";
27"ESPI_LFRAME_N_BMC_CS0_N"CDS_PHYS_NET_NAME"ESPI_LAD0_DATA_IO0";
28"IRQ_ESPI_LPC_SERIRQ_ALERT_N"CDS_PHYS_NET_NAME"FM_CPU0_SKTOCC_N";
29"RST_ESPI_RESET_N"CDS_PHYS_NET_NAME"IRQ_LPC_SERIRQ_ESPI_CS1_N";
30"RST_PLTRST_B_MUX_N"CDS_PHYS_NET_NAME"IRQ_LPC_SERIRQ_ESPI_CS1_N";
31"IRQ_LPC_PIRQA_N_ESPI_ALERT0_N"CDS_PHYS_NET_NAME"JTAG_CPU1_MUX_GTL_TDO";
32"IRQ_LPC_SERIRQ_ESPI_CS1_N"CDS_PHYS_NET_NAME"IRQ_LPC_SERIRQ_ESPI_CS1_N";
33"IRQ_LPC_SERIRQ_ESPI_CS1_R_N"CDS_PHYS_NET_NAME"IRQ_LPC_SERIRQ_ESPI_CS1_N";
34"IRQ_LPC_PIRQA_N_ESPI_ALERT0_R_N"CDS_PHYS_NET_NAME"JTAG_CPU1_MUX_GTL_TDO";
35"ESPI_HOST_LPC_BMC_CLK"CDS_PHYS_NET_NAME"ESPI_LAD0_DATA_IO3";
36"ESPI_LPC_LAD0_IO0"CDS_PHYS_NET_NAME"ESPI_LAD0_DATA_IO3";
37"ESPI_LAD0_DATA_IO1"CDS_PHYS_NET_NAME"ESPI_LAD0_DATA_IO1";
38"ESPI_LAD0_DATA_IO0"CDS_PHYS_NET_NAME"ESPI_LAD0_DATA_IO0";
39"ESPI_LAD0_DATA_IO2"CDS_PHYS_NET_NAME"ESPI_LAD0_DATA_IO2";
40"ESPI_LAD0_DATA_IO3"CDS_PHYS_NET_NAME"ESPI_LAD0_DATA_IO3";
41"CLK_24M_66M_LPC0_ESPI"CDS_PHYS_NET_NAME"ESPI_LAD0_DATA_IO0";
%"Q_RES"
"1","(-650,-250)","0","pure_quanta","I100";
;
PART_NUMBER"CS01002FB07"
MATERIAL"CHIP"
VALUE"10"
TOLERANCE"1%"
WATTAGE"1/16W"
PACK_TYPE"0402LF"
LOCATION"R1872"
CDS_LIB"pure_quanta"
$SEC"1"
CDS_SEC"1";
"B"
$PN"2"35;
"A"
$PN"1"41;
%"Q_RES"
"1","(-625,2725)","0","pure_quanta","I101";
;
PART_NUMBER"CS01002FB07"
PACK_TYPE"0402LF"
VALUE"10"
WATTAGE"1/16W"
TOLERANCE"1%"
MATERIAL"CHIP"
LOCATION"R2363"
CDS_LIB"pure_quanta"
$SEC"1"
CDS_SEC"1";
"B"
$PN"2"26;
"A"
$PN"1"29;
%"Q_RES"
"1","(-450,225)","0","pure_quanta","I102";
;
PART_NUMBER"CS01002FB07"
TOLERANCE"1%"
VALUE"10"
PACK_TYPE"0402LF"
MATERIAL"CHIP"
WATTAGE"1/16W"
LOCATION"R1479"
CDS_LIB"pure_quanta"
$SEC"1"
CDS_SEC"1";
"B"
$PN"2"25;
"A"
$PN"1"27;
%"Q_RES"
"1","(-625,3800)","0","pure_quanta","I105";
;
PART_NUMBER"CS01002FB07"
TOLERANCE"1%"
WATTAGE"1/16W"
PACK_TYPE"0402LF"
VALUE"10"
MATERIAL"CHIP"
LOCATION"R4118"
CDS_LIB"pure_quanta"
$SEC"1"
CDS_SEC"1";
"B"
$PN"2"33;
"A"
$PN"1"32;
%"UNIVERSAL_GND"
"1","(625,3500)","0","logical_power","I20";
;
CDS_LIB"logical_power"
HDL_POWER"GND";
"A"7;
%"UNIVERSAL_GND"
"1","(1875,4025)","0","logical_power","I21";
;
CDS_LIB"logical_power"
HDL_POWER"GND";
"A"8;
%"UNIVERSAL_POWER"
"1","(1400,4650)","0","logical_power","I24";
;
HDL_POWER"PGPPA_AUX"
CDS_LIB"logical_power";
"A"4;
%"Q_RES"
"1","(-625,3900)","0","pure_quanta","I33";
;
PART_NUMBER"CS00002JB13"
TOLERANCE"5%"
MATERIAL"CHIP"
PACK_TYPE"0402LF"
WATTAGE"1/16W"
VALUE"0"
$LOCATION"R1214"
CDS_LIB"pure_quanta"
CDS_LOCATION"R1214"
$SEC"1"
CDS_SEC"1";
"B"
$PN"2"34;
"A"
$PN"1"31;
%"NC7SB3157"
"1","(1000,3900)","0","pure_quanta","I34";
;
PART_NUMBER"ALSB3157000"
VALUE"NC7SB3157P6X"
MATERIAL"IC"
$LOCATION"U60"
MANUF_PN"NC7SB3157P6X"
PACK_TYPE"SMLF"
SEC_TYPE"SMLF"
CDS_LIB"pure_quanta"
CDS_LMAN_SYM_OUTLINE"-150,50,150,-150"
$LOCATION"U60"
CDS_LOCATION"U60"
SEC"1";
"S"
$PN"6"19;
"B0"
$PN"3"33;
"B1"
$PN"1"34;
"VCC"
$PN"5"4;
"GND"
$PN"2"7;
"A"
$PN"4"28;
%"Q_CAP"
"1","(1875,4350)","0","pure_quanta","I36";
;
PART_NUMBER"CH4104K1B00"
VOLTAGE"25V"
TOLERANCE"10%"
MATERIAL"X7R"
VALUE"0.1UF"
PACK_TYPE"0402"
$LOCATION"C607"
CDS_LIB"pure_quanta"
$LOCATION"C607"
CDS_LOCATION"C607"
$SEC"1"
CDS_SEC"1";
"B"
$PN"2"8;
"A"
$PN"1"4;
%"Q_CAP"
"1","(1525,4350)","0","pure_quanta","I37";
;
PART_NUMBER"CH5104KEB02"
MATERIAL"X6S"
TOLERANCE"10%"
VALUE"1UF"
PACK_TYPE"C0402"
VOLTAGE"25V"
$LOCATION"C605"
CDS_LIB"pure_quanta"
$LOCATION"C605"
CDS_LOCATION"C605"
$SEC"1"
CDS_SEC"1";
"B"
$PN"2"8;
"A"
$PN"1"4;
%"Q_RES"
"1","(2800,3800)","0","pure_quanta","I38";
;
PART_NUMBER"CS04992FB07"
PACK_TYPE"0402LF"
MATERIAL"CHIP"
WATTAGE"1/16W"
VALUE"49.9"
TOLERANCE"1%"
$LOCATION"R1215"
CDS_LIB"pure_quanta"
CDS_LOCATION"R1215"
$SEC"1"
CDS_SEC"1";
"B"
$PN"2"21;
"A"
$PN"1"28;
%"NC7SB3157"
"1","(1000,2725)","0","pure_quanta","I39";
;
PART_NUMBER"ALSB3157000"
VALUE"NC7SB3157P6X"
MATERIAL"IC"
$LOCATION"U61"
PACK_TYPE"SMLF"
SEC_TYPE"SMLF"
CDS_LIB"pure_quanta"
CDS_LMAN_SYM_OUTLINE"-150,50,150,-150"
MANUF_PN"NC7SB3157P6X"
$LOCATION"U61"
CDS_LOCATION"U61"
SEC"1";
"S"
$PN"6"19;
"B0"
$PN"3"30;
"B1"
$PN"1"26;
"VCC"
$PN"5"5;
"GND"
$PN"2"9;
"A"
$PN"4"22;
%"UNIVERSAL_GND"
"1","(625,2325)","0","logical_power","I40";
;
CDS_LIB"logical_power"
HDL_POWER"GND";
"A"9;
%"Q_CAP"
"1","(1875,3175)","0","pure_quanta","I43";
;
PART_NUMBER"CH4104K1B00"
MATERIAL"X7R"
PACK_TYPE"0402"
VALUE"0.1UF"
VOLTAGE"25V"
TOLERANCE"10%"
$LOCATION"C608"
CDS_LIB"pure_quanta"
$LOCATION"C608"
CDS_LOCATION"C608"
$SEC"1"
CDS_SEC"1";
"B"
$PN"2"10;
"A"
$PN"1"5;
%"UNIVERSAL_POWER"
"1","(1400,3475)","0","logical_power","I44";
;
HDL_POWER"PGPPA_AUX"
CDS_LIB"logical_power";
"A"5;
%"Q_CAP"
"1","(1525,3175)","0","pure_quanta","I45";
;
PART_NUMBER"CH5104KEB02"
MATERIAL"X6S"
VALUE"1UF"
PACK_TYPE"C0402"
VOLTAGE"25V"
TOLERANCE"10%"
$LOCATION"C606"
CDS_LIB"pure_quanta"
$LOCATION"C606"
CDS_LOCATION"C606"
$SEC"1"
CDS_SEC"1";
"B"
$PN"2"10;
"A"
$PN"1"5;
%"UNIVERSAL_GND"
"1","(1875,2850)","0","logical_power","I46";
;
CDS_LIB"logical_power"
HDL_POWER"GND";
"A"10;
%"Q_RES"
"1","(2800,2725)","0","pure_quanta","I54";
;
PART_NUMBER"CS00002JB13"
VALUE"0"
WATTAGE"1/16W"
PACK_TYPE"0402LF"
MATERIAL"CHIP"
TOLERANCE"5%"
$LOCATION"R1748"
CDS_LIB"pure_quanta"
CDS_LOCATION"R1748"
$SEC"1"
CDS_SEC"1";
"B"
$PN"2"20;
"A"
$PN"1"19;
%"Q_RES"
"2","(-800,550)","2","pure_quanta","I70";
;
PART_NUMBER"CS31002FB08"
MATERIAL"CHIP"
VALUE"10K"
TOLERANCE"1%"
WATTAGE"1/16W"
PACK_TYPE"0402LF"
$LOCATION"R1961"
CDS_LIB"pure_quanta"
CDS_LOCATION"R1961"
$SEC"1"
CDS_SEC"1";
"A"
$PN"1"6;
"B"
$PN"2"27;
%"UNIVERSAL_POWER"
"1","(-800,800)","0","logical_power","I71";
;
HDL_POWER"PGPPA_AUX"
CDS_LIB"logical_power";
"A"6;
%"UNIVERSAL_GND"
"1","(1175,1175)","0","logical_power","I83";
;
CDS_LIB"logical_power"
HDL_POWER"GND";
"A"11;
%"Q_CAP"
"1","(1050,1750)","2","pure_quanta","I84";
;
PART_NUMBER"CH4104K1B00"
TOLERANCE"10%"
VOLTAGE"25V"
VALUE"0.1UF"
MATERIAL"X7R"
PACK_TYPE"0402"
$LOCATION"C1647"
CDS_LIB"pure_quanta"
CDS_LOCATION"C1647"
$SEC"1"
CDS_SEC"1";
"B"
$PN"2"12;
"A"
$PN"1"2;
%"UNIVERSAL_GND"
"1","(1050,1525)","0","logical_power","I85";
;
CDS_LIB"logical_power"
HDL_POWER"GND";
"A"12;
%"UNIVERSAL_POWER"
"1","(1050,2075)","0","logical_power","I86";
;
HDL_POWER"P3V3_AUX"
CDS_LIB"logical_power";
"A"2;
%"Q_RES"
"2","(3000,1675)","0","pure_quanta","I87";
;
PART_NUMBER"CS21002FB06"
MATERIAL"CHIP"
PACK_TYPE"0402LF"
WATTAGE"1/16W"
TOLERANCE"1%"
VALUE"1K"
$LOCATION"R1750"
CDS_LIB"pure_quanta"
CDS_LOCATION"R1750"
$SEC"1"
CDS_SEC"1";
"A"
$PN"1"3;
"B"
$PN"2"14;
%"UNIVERSAL_POWER"
"1","(3000,1950)","0","logical_power","I88";
;
HDL_POWER"PGPPA_AUX"
CDS_LIB"logical_power"
BOM_COST"VR_SYSTEM ";
"A"3;
%"Q_RES"
"2","(575,1150)","0","pure_quanta","I89";
;
PART_NUMBER"CS31002FB08"
VALUE"10K"
TOLERANCE"1%"
PACK_TYPE"0402LF"
WATTAGE"1/16W"
MATERIAL"EMPTY"
$LOCATION"R1749"
CDS_LIB"pure_quanta"
CDS_LOCATION"R1749"
$SEC"1"
CDS_SEC"1";
"A"
$PN"1"16;
"B"
$PN"2"13;
%"UNIVERSAL_GND"
"1","(575,875)","0","logical_power","I90";
;
CDS_LIB"logical_power"
HDL_POWER"GND";
"A"13;
%"Q_RES"
"1","(-100,1075)","0","pure_quanta","I91";
;
PART_NUMBER"CS00002JB13"
TOLERANCE"5%"
PACK_TYPE"0402LF"
VALUE"0"
WATTAGE"1/16W"
MATERIAL"EMPTY"
$LOCATION"R2132"
CDS_LIB"pure_quanta"
CDS_LOCATION"R2132"
$SEC"1"
CDS_SEC"1";
"B"
$PN"2"16;
"A"
$PN"1"24;
%"UNIVERSAL_POWER"
"1","(25,1950)","0","logical_power","I93";
;
HDL_POWER"P3V3_AUX"
CDS_LIB"logical_power"
BOM_COST"VR_SYSTEM ";
"A"1;
%"Q_RES"
"2","(25,1675)","0","pure_quanta","I94";
;
PART_NUMBER"CS31002FB08"
PACK_TYPE"0402LF"
MATERIAL"EMPTY"
VALUE"10K"
TOLERANCE"1%"
WATTAGE"1/16W"
$LOCATION"R2451"
CDS_LIB"pure_quanta"
CDS_LOCATION"R2451"
$SEC"1"
CDS_SEC"1";
"A"
$PN"1"1;
"B"
$PN"2"16;
%"74LVC1G07SE7"
"1","(1700,1400)","0","pure_quanta","I95";
;
PART_NUMBER"AL1G07SE000"
MATERIAL"IC"
PART_TYPE"SMLF"
VALUE"74LVC1G07SE-7"
LOCATION"U154"
NEEDS_NO_SIZE"TRUE"
CDS_LMAN_SYM_OUTLINE"-150,150,150,-150"
CDS_LIB"pure_quanta"
$SEC"1"
CDS_SEC"1";
"NC1"
$PN"1"15;
"Y"
$PN"4"14;
"GND"
$PN"3"11;
"A"
$PN"2"16;
"VCC"
$PN"5"2;
%"Q_RES"
"1","(-650,-50)","0","pure_quanta","I96";
;
PART_NUMBER"CS01002FB07"
VALUE"10"
MATERIAL"CHIP"
TOLERANCE"1%"
WATTAGE"1/16W"
PACK_TYPE"0402LF"
LOCATION"R1868"
CDS_LIB"pure_quanta"
$SEC"1"
CDS_SEC"1";
"B"
$PN"2"17;
"A"
$PN"1"40;
%"Q_RES"
"1","(-650,-100)","0","pure_quanta","I97";
;
PART_NUMBER"CS01002FB07"
TOLERANCE"1%"
VALUE"10"
MATERIAL"CHIP"
WATTAGE"1/16W"
PACK_TYPE"0402LF"
LOCATION"R1869"
CDS_LIB"pure_quanta"
$SEC"1"
CDS_SEC"1";
"B"
$PN"2"18;
"A"
$PN"1"39;
%"Q_RES"
"1","(-650,-150)","0","pure_quanta","I98";
;
PART_NUMBER"CS01002FB07"
WATTAGE"1/16W"
PACK_TYPE"0402LF"
VALUE"10"
MATERIAL"CHIP"
TOLERANCE"1%"
LOCATION"R1870"
CDS_LIB"pure_quanta"
$SEC"1"
CDS_SEC"1";
"B"
$PN"2"23;
"A"
$PN"1"37;
%"Q_RES"
"1","(-650,-200)","0","pure_quanta","I99";
;
PART_NUMBER"CS01002FB07"
MATERIAL"CHIP"
VALUE"10"
WATTAGE"1/16W"
TOLERANCE"1%"
PACK_TYPE"0402LF"
LOCATION"R1871"
CDS_LIB"pure_quanta"
$SEC"1"
CDS_SEC"1";
"B"
$PN"2"36;
"A"
$PN"1"38;
END.
